(kicad_pcb
	(version 20241229)
	(generator "pcbnew")
	(generator_version "9.0")
	(general
		(thickness 0.876)
		(legacy_teardrops no)
	)
	(paper "A4")
	(title_block
		(rev "1.2.2")
		(comment 9 "footprints 20-20 of 20")
	)
	(layers
		(0 "F.Cu" signal)
		(4 "In1.Cu" signal)
		(6 "In2.Cu" signal)
		(2 "B.Cu" signal)
		(9 "F.Adhes" user "F.Adhesive")
		(11 "B.Adhes" user "B.Adhesive")
		(13 "F.Paste" user)
		(15 "B.Paste" user)
		(5 "F.SilkS" user "F.Silkscreen")
		(7 "B.SilkS" user "B.Silkscreen")
		(1 "F.Mask" user)
		(3 "B.Mask" user)
		(17 "Dwgs.User" user "User.Drawings")
		(19 "Cmts.User" user "User.Comments")
		(21 "Eco1.User" user "User.Eco1")
		(23 "Eco2.User" user "User.Eco2")
		(25 "Edge.Cuts" user)
		(27 "Margin" user)
		(31 "F.CrtYd" user "F.Courtyard")
		(29 "B.CrtYd" user "B.Courtyard")
		(35 "F.Fab" user)
		(33 "B.Fab" user)
	)
	(footprint "antmicro-footprints:antmicro-logo"
		(layer "B.Cu")
		(at 144.260059 92.357277 180)
		(property "Reference" "N1"
			(at 0.05 5.5 0)
			(layer "B.SilkS")
			(hide yes)
			(effects
				(font
					(size 0.7 0.7)
					(thickness 0.15)
				)
				(justify left bottom mirror)
			)
		)
		(property "Value" "antmicro_logo"
			(at -0.101 -5.099 0)
			(layer "B.Fab")
			(hide yes)
			(effects
				(font
					(size 0.7 0.7)
					(thickness 0.15)
				)
				(justify left bottom mirror)
			)
		)
		(property "Description" "Mechanical part"
			(at 0 0 180)
			(layer "F.Fab")
			(hide yes)
			(effects
				(font
					(size 1.27 1.27)
					(thickness 0.15)
				)
			)
		)
		(property "Author" "Antmicro"
			(at 288.520118 184.714554 0)
			(layer "B.Fab")
			(hide yes)
			(effects
				(font
					(size 1 1)
					(thickness 0.15)
				)
				(justify mirror)
			)
		)
		(property "License" "Apache-2.0"
			(at 288.520118 184.714554 0)
			(layer "B.Fab")
			(hide yes)
			(effects
				(font
					(size 1 1)
					(thickness 0.15)
				)
				(justify mirror)
			)
		)
		(property "MPN" ""
			(at 288.520118 184.714554 0)
			(layer "B.Fab")
			(hide yes)
			(effects
				(font
					(size 1 1)
					(thickness 0.15)
				)
				(justify mirror)
			)
		)
		(property "Manufacturer" ""
			(at 288.520118 184.714554 0)
			(layer "B.Fab")
			(hide yes)
			(effects
				(font
					(size 1 1)
					(thickness 0.15)
				)
				(justify mirror)
			)
		)
		(property "Public" "False"
			(at 288.520118 184.714554 0)
			(layer "B.Fab")
			(hide yes)
			(effects
				(font
					(size 1 1)
					(thickness 0.15)
				)
				(justify mirror)
			)
		)
		(sheetname "/")
		(sheetfile "m2-pcie-adapter.kicad_sch")
		(attr exclude_from_pos_files allow_soldermask_bridges)
	)
)
